FILE_TYPE = MULTI_PHYS_TABLE;
PART 'CONN36_G97614001'
{==============================================================================================================================================================================}
:PACK_TYPE | MATERIAL | PART_NUMBER     = EnvComp | PART_NUMBER  | JEDEC_TYPE               | DESCRIPTION                                     | CLASS | COMPONENT_TYPE | HEIGHT     | LEAD_LENGTH | SPEED_URL | Status |RPL| AML | Bus_Unit | Days ;
{==============================================================================================================================================================================}
'CP'       | 'CONN'   | 'G97614-001'(!) = 'YES;YES;CNC;CNC;ok;VLD' | 'G97614-001' | 'CONN36_G97614001'       | '(SYM_1) CONN,MISC,36P,MINISAS HD,VERT PF12G'   | 'IO'  | 'PRESSFIT'     | '0.550 IN' | '0.061'     | 'http://speed.intel.com:8081/speed/module/pdm/item/pdm_item_detail_direct.asp?item_cde=G97614-001&item_rev=01&url_param=unused' | 'Design' | 'NO' | '1' | 'SMO_BOARDS' | '???' 
'CP'       | 'EMPTY'  | 'G97614-001'(!) = 'YES;YES;CNC;CNC;ok;VLD' | 'G97614-001' | 'CONN36_G97614001'       | '(SYM_1) CONN,MISC,36P,MINISAS HD,VERT PF12G'   | 'IO'  | 'PRESSFIT'     | '0.550 IN' | '0.061'     | 'http://speed.intel.com:8081/speed/module/pdm/item/pdm_item_detail_direct.asp?item_cde=G97614-001&item_rev=01&url_param=unused' | 'Design' | 'NO' | '1' | 'SMO_BOARDS' | '???' 
'BP'       | 'CONN'   | 'G97614-001'(!) = 'YES;YES;CNC;CNC;ok;VLD' | 'G97614-001' | 'CONN36_G97614001'       | '(SYM_2) CONN,MISC,36P,MINISAS HD,VERT PF12G'   | 'IO'  | 'PRESSFIT'     | '0.550 IN' | '0.061'     | 'http://speed.intel.com:8081/speed/module/pdm/item/pdm_item_detail_direct.asp?item_cde=G97614-001&item_rev=01&url_param=unused' | 'Design' | 'NO' | '1' | 'SMO_BOARDS' | '???' 
'BP'       | 'EMPTY'  | 'G97614-001'(!) = 'YES;YES;CNC;CNC;ok;VLD' | 'G97614-001' | 'CONN36_G97614001'       | '(SYM_2) CONN,MISC,36P,MINISAS HD,VERT PF12G'   | 'IO'  | 'PRESSFIT'     | '0.550 IN' | '0.061'     | 'http://speed.intel.com:8081/speed/module/pdm/item/pdm_item_detail_direct.asp?item_cde=G97614-001&item_rev=01&url_param=unused' | 'Design' | 'NO' | '1' | 'SMO_BOARDS' | '???' 
END_PART
END.
